# S9S_MB_2U (Grand Teton) — schematic netlist excerpt (pin names and nets, part order shuffled) for the footprints in the layout excerpt that follows; sources: Cadence DE-HDL packaged netlist, KiCad conversion of 03242023_DA0F0TMBIJ0_F0T_Motherboard_J_brd_V01_OCP.brd

PC187  Q_CAP  2.2UF 10V 10% X6S  pkg C0402  page 275 : A = PVCCINFAON_CPU0_VDD1 ; B = GND
R4569  Q_RES  0 5% EMPTY  pkg 0402LF  page 145 : A = GPU_3V3IO_RSVD1 ; B = GPU_3V3IO_RSVD1_ISO

(kicad_pcb
	(version 20260206)
	(generator "pcbnew")
	(generator_version "10.0")
	(general
		(thickness 1.6)
		(legacy_teardrops no)
	)
	(paper "A4")
	(title_block
		(title "03242023_DA0F0TMBIJ0_F0T_Motherboard_J_brd_V01_OCP.brd")
		(comment 1 "Grand Teton / footprints 3412-3413 of 6105")
	)
	(layers
		(0 "F.Cu" signal "TOP")
		(4 "In1.Cu" signal "GND")
		(6 "In2.Cu" signal "IN1")
		(8 "In3.Cu" signal "GND1")
		(10 "In4.Cu" signal "IN2")
		(12 "In5.Cu" signal "GND2")
		(14 "In6.Cu" signal "IN3")
		(16 "In7.Cu" signal "GND3")
		(18 "In8.Cu" signal "VCC")
		(20 "In9.Cu" signal "VCC1")
		(22 "In10.Cu" signal "GND4")
		(24 "In11.Cu" signal "IN4")
		(26 "In12.Cu" signal "GND5")
		(28 "In13.Cu" signal "IN5")
		(30 "In14.Cu" signal "GND6")
		(32 "In15.Cu" signal "IN6")
		(34 "In16.Cu" signal "GND7")
		(2 "B.Cu" signal "BOTTOM")
		(9 "F.Adhes" user "F.Adhesive")
		(11 "B.Adhes" user "B.Adhesive")
		(13 "F.Paste" user "Package Geometry/Pastemask Top")
		(15 "B.Paste" user "Package Geometry/Pastemask Bottom")
		(5 "F.SilkS" user "Ref Des/Silkscreen Top")
		(7 "B.SilkS" user "Ref Des/Silkscreen Bottom")
		(1 "F.Mask" user "Board Geometry/Soldermask Top")
		(3 "B.Mask" user "Board Geometry/Soldermask Bottom")
		(17 "Dwgs.User" user "User.Drawings")
		(19 "Cmts.User" user "User.Comments")
		(21 "Eco1.User" user "User.Eco1")
		(23 "Eco2.User" user "User.Eco2")
		(25 "Edge.Cuts" user "Board Geometry/Outline")
		(27 "Margin" user)
		(31 "F.CrtYd" user "Package Geometry/Place Bound Top")
		(29 "B.CrtYd" user "Package Geometry/Place Bound Bottom")
		(35 "F.Fab" user "Ref Des/Assembly Top")
		(33 "B.Fab" user "Ref Des/Assembly Bottom")
	)
	(footprint ""
		(layer "F.Cu")
		(at 355.2444 -386.425948 180)
		(property "Reference" "R4569"
			(at 0 0 180)
			(layer "F.SilkS")
			(hide yes)
			(effects
				(font
					(size 1.27 1.27)
				)
			)
		)
		(property "Value" ""
			(at 0 0 180)
			(layer "F.Fab")
			(effects
				(font
					(size 1.27 1.27)
				)
			)
		)
		(duplicate_pad_numbers_are_jumpers no)
		(fp_line
			(start 0.7874 0.4064)
			(end -0.7874 0.4064)
			(stroke
				(width 0.1524)
				(type default)
			)
			(layer "F.SilkS")
		)
		(fp_line
			(start 0.7874 -0.4064)
			(end 0.7874 0.4064)
			(stroke
				(width 0.1524)
				(type default)
			)
			(layer "F.SilkS")
		)
		(fp_line
			(start -0.7874 0.4064)
			(end -0.7874 -0.4064)
			(stroke
				(width 0.1524)
				(type default)
			)
			(layer "F.SilkS")
		)
		(fp_line
			(start -0.7874 -0.4064)
			(end 0.7874 -0.4064)
			(stroke
				(width 0.1524)
				(type default)
			)
			(layer "F.SilkS")
		)
		(fp_line
			(start 0.67945 0.3048)
			(end 0.120396 0.3048)
			(stroke
				(width 0.1)
				(type default)
			)
			(layer "F.Fab")
		)
		(fp_line
			(start 0.67945 -0.3048)
			(end 0.67945 0.3048)
			(stroke
				(width 0.1)
				(type default)
			)
			(layer "F.Fab")
		)
		(fp_line
			(start 0.12065 -0.2794)
			(end 0.12065 -0.3048)
			(stroke
				(width 0.1)
				(type default)
			)
			(layer "F.Fab")
		)
		(fp_line
			(start 0.12065 -0.3048)
			(end 0.67945 -0.3048)
			(stroke
				(width 0.1)
				(type default)
			)
			(layer "F.Fab")
		)
		(fp_line
			(start 0.120396 0.3048)
			(end 0.120396 0.2794)
			(stroke
				(width 0.1)
				(type default)
			)
			(layer "F.Fab")
		)
		(fp_line
			(start 0.120396 0.2794)
			(end -0.12065 0.2794)
			(stroke
				(width 0.1)
				(type default)
			)
			(layer "F.Fab")
		)
		(fp_line
			(start -0.12065 0.3048)
			(end -0.67945 0.3048)
			(stroke
				(width 0.1)
				(type default)
			)
			(layer "F.Fab")
		)
		(fp_line
			(start -0.12065 0.2794)
			(end -0.12065 0.3048)
			(stroke
				(width 0.1)
				(type default)
			)
			(layer "F.Fab")
		)
		(fp_line
			(start -0.12065 -0.2794)
			(end 0.12065 -0.2794)
			(stroke
				(width 0.1)
				(type default)
			)
			(layer "F.Fab")
		)
		(fp_line
			(start -0.12065 -0.305054)
			(end -0.12065 -0.2794)
			(stroke
				(width 0.1)
				(type default)
			)
			(layer "F.Fab")
		)
		(fp_line
			(start -0.67945 0.3048)
			(end -0.67945 -0.305054)
			(stroke
				(width 0.1)
				(type default)
			)
			(layer "F.Fab")
		)
		(fp_line
			(start -0.67945 -0.305054)
			(end -0.12065 -0.305054)
			(stroke
				(width 0.1)
				(type default)
			)
			(layer "F.Fab")
		)
		(pad "1" smd circle
			(at -0.40005 0 180)
			(size 0 0)
			(layers "F.Cu" "F.Mask" "F.Paste")
			(net "GPU_3V3IO_RSVD1")
		)
		(pad "2" smd circle
			(at 0.40005 0 180)
			(size 0 0)
			(layers "F.Cu" "F.Mask" "F.Paste")
			(net "GPU_3V3IO_RSVD1_ISO")
		)
	)
	(footprint ""
		(layer "F.Cu")
		(at 418.485828 -174.396654)
		(property "Reference" "PC187"
			(at 0 0 0)
			(layer "F.SilkS")
			(hide yes)
			(effects
				(font
					(size 1.27 1.27)
				)
			)
		)
		(property "Value" ""
			(at 0 0 0)
			(layer "F.Fab")
			(effects
				(font
					(size 1.27 1.27)
				)
			)
		)
		(duplicate_pad_numbers_are_jumpers no)
		(fp_line
			(start -0.7874 -0.4064)
			(end 0.7874 -0.4064)
			(stroke
				(width 0.1524)
				(type default)
			)
			(layer "F.SilkS")
		)
		(fp_line
			(start -0.7874 0.4064)
			(end -0.7874 -0.4064)
			(stroke
				(width 0.1524)
				(type default)
			)
			(layer "F.SilkS")
		)
		(fp_line
			(start 0.7874 -0.4064)
			(end 0.7874 0.4064)
			(stroke
				(width 0.1524)
				(type default)
			)
			(layer "F.SilkS")
		)
		(fp_line
			(start 0.7874 0.4064)
			(end -0.7874 0.4064)
			(stroke
				(width 0.1524)
				(type default)
			)
			(layer "F.SilkS")
		)
		(fp_line
			(start -0.67945 -0.305054)
			(end -0.12065 -0.305054)
			(stroke
				(width 0.1)
				(type default)
			)
			(layer "F.Fab")
		)
		(fp_line
			(start -0.67945 0.3048)
			(end -0.67945 -0.305054)
			(stroke
				(width 0.1)
				(type default)
			)
			(layer "F.Fab")
		)
		(fp_line
			(start -0.12065 -0.305054)
			(end -0.12065 -0.2794)
			(stroke
				(width 0.1)
				(type default)
			)
			(layer "F.Fab")
		)
		(fp_line
			(start -0.12065 -0.2794)
			(end 0.12065 -0.2794)
			(stroke
				(width 0.1)
				(type default)
			)
			(layer "F.Fab")
		)
		(fp_line
			(start -0.12065 0.2794)
			(end -0.12065 0.3048)
			(stroke
				(width 0.1)
				(type default)
			)
			(layer "F.Fab")
		)
		(fp_line
			(start -0.12065 0.3048)
			(end -0.67945 0.3048)
			(stroke
				(width 0.1)
				(type default)
			)
			(layer "F.Fab")
		)
		(fp_line
			(start 0.120396 0.2794)
			(end -0.12065 0.2794)
			(stroke
				(width 0.1)
				(type default)
			)
			(layer "F.Fab")
		)
		(fp_line
			(start 0.120396 0.3048)
			(end 0.120396 0.2794)
			(stroke
				(width 0.1)
				(type default)
			)
			(layer "F.Fab")
		)
		(fp_line
			(start 0.12065 -0.3048)
			(end 0.67945 -0.3048)
			(stroke
				(width 0.1)
				(type default)
			)
			(layer "F.Fab")
		)
		(fp_line
			(start 0.12065 -0.2794)
			(end 0.12065 -0.3048)
			(stroke
				(width 0.1)
				(type default)
			)
			(layer "F.Fab")
		)
		(fp_line
			(start 0.67945 -0.3048)
			(end 0.67945 0.3048)
			(stroke
				(width 0.1)
				(type default)
			)
			(layer "F.Fab")
		)
		(fp_line
			(start 0.67945 0.3048)
			(end 0.120396 0.3048)
			(stroke
				(width 0.1)
				(type default)
			)
			(layer "F.Fab")
		)
		(pad "1" smd circle
			(at -0.40005 0)
			(size 0 0)
			(layers "F.Cu" "F.Mask" "F.Paste")
			(net "PVCCINFAON_CPU0_VDD1")
		)
		(pad "2" smd circle
			(at 0.40005 0)
			(size 0 0)
			(layers "F.Cu" "F.Mask" "F.Paste")
			(net "GND")
		)
	)
)
